# S9S_MB_2U (Grand Teton) — schematic netlist excerpt (pin names and nets, part order shuffled) for the footprints in the layout excerpt that follows; sources: Cadence DE-HDL packaged netlist, KiCad conversion of 03242023_DA0F0TMBIJ0_F0T_Motherboard_J_brd_V01_OCP.brd

J35  SCONN168_ME1016810202011  IO  pkg CON_F168S2H7D_P0-6W2-95_LUH  page 159
  GND_A1  = GND
  GND_A2  = GND
  GND_A3  = GND
  GND_A4  = GND
  GND_A5  = GND
  GND_A6  = GND
  SMCLK  = SMB_OCP_V3_2_3V3AUX_BUF_R_SCL
  SMDAT  = SMB_OCP_V3_2_3V3AUX_BUF_R_SDA
  \smrst#\  = RST_SMB_OCP_V3_2_N
  \prsnta#\  = OCP_V3_1_PRSNTA_R_N
  \perst1#\  = RST_PERST1_OCP_V3_2_N
  \prsntb2#\  = OCP_V3_2_PRSNT2_R_N
  GND_A13  = GND
  REFCLKN1  = CLK_100M_OCP_V3_2_B_DN
  REFCLKP1  = CLK_100M_OCP_V3_2_B_DP
  GND_A16  = GND
  PERN0  = P5E_CPU1_PE1_RX_DN<0>
  PERP0  = P5E_CPU1_PE1_RX_DP<0>
  GND_A19  = GND
  PERN1  = P5E_CPU1_PE1_RX_DN<1>
  PERP1  = P5E_CPU1_PE1_RX_DP<1>
  GND_A22  = GND
  PERN2  = P5E_CPU1_PE1_RX_DN<2>
  PERP2  = P5E_CPU1_PE1_RX_DP<2>
  GND_A25  = GND
  PERN3  = P5E_CPU1_PE1_RX_DN<3>
  PERP3  = P5E_CPU1_PE1_RX_DP<3>
  GND_A28  = GND
  GND_A29  = GND
  PERN4  = P5E_CPU1_PE1_RX_DN<4>
  PERP4  = P5E_CPU1_PE1_RX_DP<4>
  GND_A32  = GND
  PERN5  = P5E_CPU1_PE1_RX_DN<5>
  PERP5  = P5E_CPU1_PE1_RX_DP<5>
  GND_A35  = GND
  PERN6  = P5E_CPU1_PE1_RX_DN<6>
  PERP6  = P5E_CPU1_PE1_RX_DP<6>
  GND_A38  = GND
  PERN7  = P5E_CPU1_PE1_RX_DN<7>
  PERP7  = P5E_CPU1_PE1_RX_DP<7>
  GND_A41  = GND
  \prsntb1#\  = OCP_V3_2_PRSNT1_R_N
  GND_A43  = GND
  PERN8  = P5E_CPU1_PE1_RX_DN<8>
  PERP8  = P5E_CPU1_PE1_RX_DP<8>
  GND_A46  = GND
  PERN9  = P5E_CPU1_PE1_RX_DN<9>
  PERP9  = P5E_CPU1_PE1_RX_DP<9>
  GND_A49  = GND
  PERN10  = P5E_CPU1_PE1_RX_DN<10>
  PERP10  = P5E_CPU1_PE1_RX_DP<10>
  GND_A52  = GND
  PERN11  = P5E_CPU1_PE1_RX_DN<11>
  PERP11  = P5E_CPU1_PE1_RX_DP<11>
  GND_A55  = GND
  PERN12  = P5E_CPU1_PE1_RX_DN<12>
  PERP12  = P5E_CPU1_PE1_RX_DP<12>
  GND_A58  = GND
  PERN13  = P5E_CPU1_PE1_RX_DN<13>
  PERP13  = P5E_CPU1_PE1_RX_DP<13>
  GND_A61  = GND
  PERN14  = P5E_CPU1_PE1_RX_DN<14>
  PERP14  = P5E_CPU1_PE1_RX_DP<14>
  GND_A64  = GND
  PERN15  = P5E_CPU1_PE1_RX_DN<15>
  PERP15  = P5E_CPU1_PE1_RX_DP<15>
  GND_A67  = GND
  USB_DATN  = USB2_5_R1_DN
  USB_DATP  = USB2_5_R1_DP
  \pwrbrk0#\  = OCP_V3_2_PWRBRK_N
  \+12v_edge_b1\  = P12V_OCP_V3_2
  \+12v_edge_b2\  = P12V_OCP_V3_2
  \+12v_edge_b3\  = P12V_OCP_V3_2
  \+12v_edge_b4\  = P12V_OCP_V3_2
  \+12v_edge_b5\  = P12V_OCP_V3_2
  \+12v_edge_b6\  = P12V_OCP_V3_2
  \bif0#\  = OCP_V3_2_BIF0_R_N
  \bif1#\  = OCP_V3_2_BIF1_R_N
  \bif2#\  = OCP_V3_2_BIF2_R_N
  \perst0#\  = RST_PERST0_OCP_V3_2_N
  \+3.3v_edge\  = P3V3_OCP_V3_2
  AUX_PWR_EN  = OCP_V3_2_AUX_PWR_EN_R
  GND_B13  = GND
  REFCLKN0  = CLK_100M_OCP_V3_2_A_DN
  REFCLKP0  = CLK_100M_OCP_V3_2_A_DP
  GND_B16  = GND
  PETN0  = P5E_CPU1_PE1_TX_C_DP<0>
  PETP0  = P5E_CPU1_PE1_TX_C_DN<0>
  GND_B19  = GND
  PETN1  = P5E_CPU1_PE1_TX_C_DN<1>
  PETP1  = P5E_CPU1_PE1_TX_C_DP<1>
  GND_B22  = GND
  PETN2  = P5E_CPU1_PE1_TX_C_DP<2>
  PETP2  = P5E_CPU1_PE1_TX_C_DN<2>
  GND_B25  = GND
  PETN3  = P5E_CPU1_PE1_TX_C_DN<3>
  PETP3  = P5E_CPU1_PE1_TX_C_DP<3>
  GND_B28  = GND
  GND_B29  = GND
  PETN4  = P5E_CPU1_PE1_TX_C_DP<4>
  PETP4  = P5E_CPU1_PE1_TX_C_DN<4>
  GND_B32  = GND
  PETN5  = P5E_CPU1_PE1_TX_C_DN<5>
  PETP5  = P5E_CPU1_PE1_TX_C_DP<5>
  GND_B35  = GND
  PETN6  = P5E_CPU1_PE1_TX_C_DP<6>
  PETP6  = P5E_CPU1_PE1_TX_C_DN<6>
  GND_B38  = GND
  PETN7  = P5E_CPU1_PE1_TX_C_DN<7>
  PETP7  = P5E_CPU1_PE1_TX_C_DP<7>
  GND_B41  = GND
  \prsntb0#\  = OCP_V3_2_PRSNT0_R_N
  GND_B43  = GND
  PETN8  = P5E_CPU1_PE1_TX_C_DP<8>
  PETP8  = P5E_CPU1_PE1_TX_C_DN<8>
  GND_B46  = GND
  PETN9  = P5E_CPU1_PE1_TX_C_DN<9>
  PETP9  = P5E_CPU1_PE1_TX_C_DP<9>
  GND_B49  = GND
  PETN10  = P5E_CPU1_PE1_TX_C_DP<10>
  PETP10  = P5E_CPU1_PE1_TX_C_DN<10>
  GND_B52  = GND
  PETN11  = P5E_CPU1_PE1_TX_C_DN<11>
  PETP11  = P5E_CPU1_PE1_TX_C_DP<11>
  GND_B55  = GND
  PETN12  = P5E_CPU1_PE1_TX_C_DP<12>
  PETP12  = P5E_CPU1_PE1_TX_C_DN<12>
  GND_B58  = GND
  PETN13  = P5E_CPU1_PE1_TX_C_DN<13>
  PETP13  = P5E_CPU1_PE1_TX_C_DP<13>
  GND_B61  = GND
  PETN14  = P5E_CPU1_PE1_TX_C_DP<14>
  PETP14  = P5E_CPU1_PE1_TX_C_DN<14>
  GND_B64  = GND
  PETN15  = P5E_CPU1_PE1_TX_C_DN<15>
  PETP15  = P5E_CPU1_PE1_TX_C_DP<15>
  GND_B67  = GND
  RFU1_NC_B68  = TP_OCP_V3_2_B68
  RFU1_NC_B69  = TP_OCP_V3_2_B69
  \prsntb3#\  = OCP_V3_2_PRSNT3_R_N
  G1  = GND
  G2  = GND
  G3  = GND
  G4  = GND
  G5  = GND
  \perst2#\  = RST_PERST2_OCP_V3_2_N
  \perst3#\  = RST_PERST3_OCP_V3_2_N
  \wake#\  = IRQ_LVC3_OCP_V3_2_WAKE_N
  RBT_ARB_IN  = OCP_V3_2_ISO1_RBT_ARB_IN
  RBT_ARB_OUT  = OCP_V3_2_ISO2_RBT_ARB_OUT
  SLOT_ID1  = OCP_V3_2_ID1
  RBT_TX_EN  = NCSI_OCP_V3_2_TX_EN
  RBT_TXD1  = NCSI_OCP_V3_2_TXD1
  RBT_TXD0  = NCSI_OCP_V3_2_TXD0
  GND_OA10  = GND
  REFCLKN3  = CLK_100M_OCP_V3_2_D_DN
  REFCLKP3  = CLK_100M_OCP_V3_2_D_DP
  GND_OA13  = GND
  RBT_CLK_IN  = CLK_50M_NCSI_OCP_V3_2_ISO
  NIC_PWR_GOOD  = FM_OCP_V3_2_PWR_GOOD
  MAIN_PWR_EN  = OCP_V3_2_MAIN_PWR_EN_R
  \ld#\  = SGPIO_OCP_V3_2_LD_N
  DATA_IN  = SGPIO_OCP_V3_2_DATAIN
  DATA_OUT  = SGPIO_OCP_V3_2_DATAOUT
  CLK  = SGPIO_OCP_V3_2_CLK
  SLOT_ID0  = OCP_V3_2_ID0
  RBT_RXD1  = NCSI_OCP_V3_2_RXD1
  RBT_RXD0  = NCSI_OCP_V3_2_RXD0
  GND_OB10  = GND
  REFCLKN2  = CLK_100M_OCP_V3_2_C_DN
  REFCLKP2  = CLK_100M_OCP_V3_2_C_DP
  GND_OB13  = GND
  RBT_CRS_DV  = NCSI_OCP_V3_2_CRS_DV

(kicad_pcb
	(version 20260206)
	(generator "pcbnew")
	(generator_version "10.0")
	(general
		(thickness 1.6)
		(legacy_teardrops no)
	)
	(paper "A4")
	(title_block
		(title "03242023_DA0F0TMBIJ0_F0T_Motherboard_J_brd_V01_OCP.brd")
		(comment 1 "Grand Teton / footprint 3456 of 6105 (J35), pads 1-44 of 175")
	)
	(layers
		(0 "F.Cu" signal "TOP")
		(4 "In1.Cu" signal "GND")
		(6 "In2.Cu" signal "IN1")
		(8 "In3.Cu" signal "GND1")
		(10 "In4.Cu" signal "IN2")
		(12 "In5.Cu" signal "GND2")
		(14 "In6.Cu" signal "IN3")
		(16 "In7.Cu" signal "GND3")
		(18 "In8.Cu" signal "VCC")
		(20 "In9.Cu" signal "VCC1")
		(22 "In10.Cu" signal "GND4")
		(24 "In11.Cu" signal "IN4")
		(26 "In12.Cu" signal "GND5")
		(28 "In13.Cu" signal "IN5")
		(30 "In14.Cu" signal "GND6")
		(32 "In15.Cu" signal "IN6")
		(34 "In16.Cu" signal "GND7")
		(2 "B.Cu" signal "BOTTOM")
		(9 "F.Adhes" user "F.Adhesive")
		(11 "B.Adhes" user "B.Adhesive")
		(13 "F.Paste" user "Package Geometry/Pastemask Top")
		(15 "B.Paste" user "Package Geometry/Pastemask Bottom")
		(5 "F.SilkS" user "Ref Des/Silkscreen Top")
		(7 "B.SilkS" user "Ref Des/Silkscreen Bottom")
		(1 "F.Mask" user "Board Geometry/Soldermask Top")
		(3 "B.Mask" user "Board Geometry/Soldermask Bottom")
		(17 "Dwgs.User" user "User.Drawings")
		(19 "Cmts.User" user "User.Comments")
		(21 "Eco1.User" user "User.Eco1")
		(23 "Eco2.User" user "User.Eco2")
		(25 "Edge.Cuts" user "Board Geometry/Outline")
		(27 "Margin" user)
		(31 "F.CrtYd" user "Package Geometry/Place Bound Top")
		(29 "B.CrtYd" user "Package Geometry/Place Bound Bottom")
		(35 "F.Fab" user "Ref Des/Assembly Top")
		(33 "B.Fab" user "Ref Des/Assembly Bottom")
	)
	(footprint ""
		(layer "F.Cu")
		(at 47.401988 -5.569966 -90)
		(property "Reference" "J35"
			(at -16.848074 29.242004 0)
			(unlocked yes)
			(layer "F.SilkS")
			(effects
				(font
					(size 0.7874 0.5842)
					(thickness 0.1524)
				)
				(justify left)
			)
		)
		(property "Value" ""
			(at 0 0 270)
			(layer "F.Fab")
			(effects
				(font
					(size 1.27 1.27)
				)
			)
		)
		(duplicate_pad_numbers_are_jumpers no)
		(pad "" np_thru_hole circle
			(at -0.599948 -32.079946 180)
			(size 1.1176 1.1176)
			(drill 1.1176)
			(layers "*.Cu" "*.Mask")
			(clearance 0.381)
			(thermal_gap 0.381)
		)
		(pad "" np_thru_hole circle
			(at 0.40005 32.085026 180)
			(size 1.1176 1.1176)
			(drill 1.1176)
			(layers "*.Cu" "*.Mask")
			(clearance 0.381)
			(thermal_gap 0.381)
		)
		(pad "A1" smd rect
			(at -2.750058 -18.465038 180)
			(size 0.381 1.4478)
			(layers "F.Cu" "F.Mask" "F.Paste")
			(net "GND")
		)
		(pad "A2" smd rect
			(at -2.750058 -17.86509 180)
			(size 0.381 1.4478)
			(layers "F.Cu" "F.Mask" "F.Paste")
			(net "GND")
		)
		(pad "A3" smd rect
			(at -2.750058 -17.264888 180)
			(size 0.381 1.4478)
			(layers "F.Cu" "F.Mask" "F.Paste")
			(net "GND")
		)
		(pad "A4" smd rect
			(at -2.750058 -16.66494 180)
			(size 0.381 1.4478)
			(layers "F.Cu" "F.Mask" "F.Paste")
			(net "GND")
		)
		(pad "A5" smd rect
			(at -2.750058 -16.064992 180)
			(size 0.381 1.4478)
			(layers "F.Cu" "F.Mask" "F.Paste")
			(net "GND")
		)
		(pad "A6" smd rect
			(at -2.750058 -15.465044 180)
			(size 0.381 1.4478)
			(layers "F.Cu" "F.Mask" "F.Paste")
			(net "GND")
		)
		(pad "A7" smd rect
			(at -2.750058 -14.865096 180)
			(size 0.381 1.4478)
			(layers "F.Cu" "F.Mask" "F.Paste")
			(net "SMB_OCP_V3_2_3V3AUX_BUF_R_SCL")
		)
		(pad "A8" smd rect
			(at -2.750058 -14.264894 180)
			(size 0.381 1.4478)
			(layers "F.Cu" "F.Mask" "F.Paste")
			(net "SMB_OCP_V3_2_3V3AUX_BUF_R_SDA")
		)
		(pad "A9" smd rect
			(at -2.750058 -13.664946 180)
			(size 0.381 1.4478)
			(layers "F.Cu" "F.Mask" "F.Paste")
			(net "RST_SMB_OCP_V3_2_N")
		)
		(pad "A10" smd rect
			(at -2.750058 -13.064998 180)
			(size 0.381 1.4478)
			(layers "F.Cu" "F.Mask" "F.Paste")
			(net "OCP_V3_1_PRSNTA_R_N")
		)
		(pad "A11" smd rect
			(at -2.750058 -12.46505 180)
			(size 0.381 1.4478)
			(layers "F.Cu" "F.Mask" "F.Paste")
			(net "RST_PERST1_OCP_V3_2_N")
		)
		(pad "A12" smd rect
			(at -2.750058 -11.865102 180)
			(size 0.381 1.4478)
			(layers "F.Cu" "F.Mask" "F.Paste")
			(net "OCP_V3_2_PRSNT2_R_N")
		)
		(pad "A13" smd rect
			(at -2.750058 -11.2649 180)
			(size 0.381 1.4478)
			(layers "F.Cu" "F.Mask" "F.Paste")
			(net "GND")
		)
		(pad "A14" smd rect
			(at -2.750058 -10.664952 180)
			(size 0.381 1.4478)
			(layers "F.Cu" "F.Mask" "F.Paste")
			(net "CLK_100M_OCP_V3_2_B_DN")
		)
		(pad "A15" smd rect
			(at -2.750058 -10.065004 180)
			(size 0.381 1.4478)
			(layers "F.Cu" "F.Mask" "F.Paste")
			(net "CLK_100M_OCP_V3_2_B_DP")
		)
		(pad "A16" smd rect
			(at -2.750058 -9.465056 180)
			(size 0.381 1.4478)
			(layers "F.Cu" "F.Mask" "F.Paste")
			(net "GND")
		)
		(pad "A17" smd rect
			(at -2.750058 -8.865108 180)
			(size 0.381 1.4478)
			(layers "F.Cu" "F.Mask" "F.Paste")
			(net "P5E_CPU1_PE1_RX_DN<0>")
		)
		(pad "A18" smd rect
			(at -2.750058 -8.264906 180)
			(size 0.381 1.4478)
			(layers "F.Cu" "F.Mask" "F.Paste")
			(net "P5E_CPU1_PE1_RX_DP<0>")
		)
		(pad "A19" smd rect
			(at -2.750058 -7.664958 180)
			(size 0.381 1.4478)
			(layers "F.Cu" "F.Mask" "F.Paste")
			(net "GND")
		)
		(pad "A20" smd rect
			(at -2.750058 -7.06501 180)
			(size 0.381 1.4478)
			(layers "F.Cu" "F.Mask" "F.Paste")
			(net "P5E_CPU1_PE1_RX_DN<1>")
		)
		(pad "A21" smd rect
			(at -2.750058 -6.465062 180)
			(size 0.381 1.4478)
			(layers "F.Cu" "F.Mask" "F.Paste")
			(net "P5E_CPU1_PE1_RX_DP<1>")
		)
		(pad "A22" smd rect
			(at -2.750058 -5.865114 180)
			(size 0.381 1.4478)
			(layers "F.Cu" "F.Mask" "F.Paste")
			(net "GND")
		)
		(pad "A23" smd rect
			(at -2.750058 -5.264912 180)
			(size 0.381 1.4478)
			(layers "F.Cu" "F.Mask" "F.Paste")
			(net "P5E_CPU1_PE1_RX_DN<2>")
		)
		(pad "A24" smd rect
			(at -2.750058 -4.664964 180)
			(size 0.381 1.4478)
			(layers "F.Cu" "F.Mask" "F.Paste")
			(net "P5E_CPU1_PE1_RX_DP<2>")
		)
		(pad "A25" smd rect
			(at -2.750058 -4.065016 180)
			(size 0.381 1.4478)
			(layers "F.Cu" "F.Mask" "F.Paste")
			(net "GND")
		)
		(pad "A26" smd rect
			(at -2.750058 -3.465068 180)
			(size 0.381 1.4478)
			(layers "F.Cu" "F.Mask" "F.Paste")
			(net "P5E_CPU1_PE1_RX_DN<3>")
		)
		(pad "A27" smd rect
			(at -2.750058 -2.86512 180)
			(size 0.381 1.4478)
			(layers "F.Cu" "F.Mask" "F.Paste")
			(net "P5E_CPU1_PE1_RX_DP<3>")
		)
		(pad "A28" smd rect
			(at -2.750058 -2.264918 180)
			(size 0.381 1.4478)
			(layers "F.Cu" "F.Mask" "F.Paste")
			(net "GND")
		)
		(pad "A29" smd rect
			(at -2.750058 1.74498 180)
			(size 0.381 1.4478)
			(layers "F.Cu" "F.Mask" "F.Paste")
			(net "GND")
		)
		(pad "A30" smd rect
			(at -2.750058 2.344928 180)
			(size 0.381 1.4478)
			(layers "F.Cu" "F.Mask" "F.Paste")
			(net "P5E_CPU1_PE1_RX_DN<4>")
		)
		(pad "A31" smd rect
			(at -2.750058 2.944876 180)
			(size 0.381 1.4478)
			(layers "F.Cu" "F.Mask" "F.Paste")
			(net "P5E_CPU1_PE1_RX_DP<4>")
		)
		(pad "A32" smd rect
			(at -2.750058 3.545078 180)
			(size 0.381 1.4478)
			(layers "F.Cu" "F.Mask" "F.Paste")
			(net "GND")
		)
		(pad "A33" smd rect
			(at -2.750058 4.145026 180)
			(size 0.381 1.4478)
			(layers "F.Cu" "F.Mask" "F.Paste")
			(net "P5E_CPU1_PE1_RX_DN<5>")
		)
		(pad "A34" smd rect
			(at -2.750058 4.744974 180)
			(size 0.381 1.4478)
			(layers "F.Cu" "F.Mask" "F.Paste")
			(net "P5E_CPU1_PE1_RX_DP<5>")
		)
		(pad "A35" smd rect
			(at -2.750058 5.344922 180)
			(size 0.381 1.4478)
			(layers "F.Cu" "F.Mask" "F.Paste")
			(net "GND")
		)
		(pad "A36" smd rect
			(at -2.750058 5.945124 180)
			(size 0.381 1.4478)
			(layers "F.Cu" "F.Mask" "F.Paste")
			(net "P5E_CPU1_PE1_RX_DN<6>")
		)
		(pad "A37" smd rect
			(at -2.750058 6.545072 180)
			(size 0.381 1.4478)
			(layers "F.Cu" "F.Mask" "F.Paste")
			(net "P5E_CPU1_PE1_RX_DP<6>")
		)
		(pad "A38" smd rect
			(at -2.750058 7.14502 180)
			(size 0.381 1.4478)
			(layers "F.Cu" "F.Mask" "F.Paste")
			(net "GND")
		)
		(pad "A39" smd rect
			(at -2.750058 7.744968 180)
			(size 0.381 1.4478)
			(layers "F.Cu" "F.Mask" "F.Paste")
			(net "P5E_CPU1_PE1_RX_DN<7>")
		)
		(pad "A40" smd rect
			(at -2.750058 8.344916 180)
			(size 0.381 1.4478)
			(layers "F.Cu" "F.Mask" "F.Paste")
			(net "P5E_CPU1_PE1_RX_DP<7>")
		)
		(pad "A41" smd rect
			(at -2.750058 8.945118 180)
			(size 0.381 1.4478)
			(layers "F.Cu" "F.Mask" "F.Paste")
			(net "GND")
		)
		(pad "A42" smd rect
			(at -2.750058 9.545066 180)
			(size 0.381 1.4478)
			(layers "F.Cu" "F.Mask" "F.Paste")
			(net "OCP_V3_2_PRSNT1_R_N")
		)
	)
)
